# SCM (Grand Teton) — schematic netlist excerpt (pin names and nets, part order shuffled) for the footprints in the layout excerpt that follows; sources: Cadence DE-HDL packaged netlist, KiCad conversion of 12092022_DA0F0TMDCD0_F0T_Management_Board_D_brd_V3_OCP.brd

R744  Q_RES  100 1% EMPTY  pkg 0402LF  page 28 : A = LED_POSTCODE_A1 ; B = GND
R251  Q_RES  499 1% CHIP  pkg 0402LF  page 27 : A = P3V3_AUX ; B = SMB_BMC_MM4_SDA

(kicad_pcb
	(version 20260206)
	(generator "pcbnew")
	(generator_version "10.0")
	(general
		(thickness 1.6)
		(legacy_teardrops no)
	)
	(paper "A4")
	(title_block
		(title "12092022_DA0F0TMDCD0_F0T_Management_Board_D_brd_V3_OCP.brd")
		(comment 1 "Grand Teton / footprints 1145-1146 of 1440")
	)
	(layers
		(0 "F.Cu" signal "TOP")
		(4 "In1.Cu" signal "GND")
		(6 "In2.Cu" signal "IN1")
		(8 "In3.Cu" signal "GND1")
		(10 "In4.Cu" signal "IN2")
		(12 "In5.Cu" signal "VCC")
		(14 "In6.Cu" signal "VCC1")
		(16 "In7.Cu" signal "IN3")
		(18 "In8.Cu" signal "GND2")
		(20 "In9.Cu" signal "IN4")
		(22 "In10.Cu" signal "GND3")
		(2 "B.Cu" signal "BOTTOM")
		(9 "F.Adhes" user "F.Adhesive")
		(11 "B.Adhes" user "B.Adhesive")
		(13 "F.Paste" user "Package Geometry/Pastemask Top")
		(15 "B.Paste" user "Package Geometry/Pastemask Bottom")
		(5 "F.SilkS" user "Ref Des/Silkscreen Top")
		(7 "B.SilkS" user "Ref Des/Silkscreen Bottom")
		(1 "F.Mask" user "Board Geometry/Soldermask Top")
		(3 "B.Mask" user "Board Geometry/Soldermask Bottom")
		(17 "Dwgs.User" user "User.Drawings")
		(19 "Cmts.User" user "User.Comments")
		(21 "Eco1.User" user "User.Eco1")
		(23 "Eco2.User" user "User.Eco2")
		(25 "Edge.Cuts" user "Board Geometry/Outline")
		(27 "Margin" user)
		(31 "F.CrtYd" user "Package Geometry/Place Bound Top")
		(29 "B.CrtYd" user "Package Geometry/Place Bound Bottom")
		(35 "F.Fab" user "Ref Des/Assembly Top")
		(33 "B.Fab" user "Ref Des/Assembly Bottom")
	)
	(footprint ""
		(layer "B.Cu")
		(at 63.9572 -92.2274 180)
		(property "Reference" "R744"
			(at 0 0 0)
			(layer "B.SilkS")
			(hide yes)
			(effects
				(font
					(size 1.27 1.27)
				)
				(justify mirror)
			)
		)
		(property "Value" ""
			(at 0 0 0)
			(layer "B.Fab")
			(effects
				(font
					(size 1.27 1.27)
				)
				(justify mirror)
			)
		)
		(duplicate_pad_numbers_are_jumpers no)
		(fp_line
			(start 0.7874 0.4064)
			(end 0.7874 -0.4064)
			(stroke
				(width 0.1524)
				(type default)
			)
			(layer "B.SilkS")
		)
		(fp_line
			(start 0.7874 -0.4064)
			(end -0.7874 -0.4064)
			(stroke
				(width 0.1524)
				(type default)
			)
			(layer "B.SilkS")
		)
		(fp_line
			(start -0.7874 0.4064)
			(end 0.7874 0.4064)
			(stroke
				(width 0.1524)
				(type default)
			)
			(layer "B.SilkS")
		)
		(fp_line
			(start -0.7874 -0.4064)
			(end -0.7874 0.4064)
			(stroke
				(width 0.1524)
				(type default)
			)
			(layer "B.SilkS")
		)
		(fp_line
			(start 0.67945 0.3048)
			(end 0.67945 -0.305054)
			(stroke
				(width 0.1)
				(type default)
			)
			(layer "B.Fab")
		)
		(fp_line
			(start 0.67945 -0.305054)
			(end 0.12065 -0.305054)
			(stroke
				(width 0.1)
				(type default)
			)
			(layer "B.Fab")
		)
		(fp_line
			(start 0.12065 0.3048)
			(end 0.67945 0.3048)
			(stroke
				(width 0.1)
				(type default)
			)
			(layer "B.Fab")
		)
		(fp_line
			(start 0.12065 0.2794)
			(end 0.12065 0.3048)
			(stroke
				(width 0.1)
				(type default)
			)
			(layer "B.Fab")
		)
		(fp_line
			(start 0.12065 -0.2794)
			(end -0.12065 -0.2794)
			(stroke
				(width 0.1)
				(type default)
			)
			(layer "B.Fab")
		)
		(fp_line
			(start 0.12065 -0.305054)
			(end 0.12065 -0.2794)
			(stroke
				(width 0.1)
				(type default)
			)
			(layer "B.Fab")
		)
		(fp_line
			(start -0.120396 0.3048)
			(end -0.120396 0.2794)
			(stroke
				(width 0.1)
				(type default)
			)
			(layer "B.Fab")
		)
		(fp_line
			(start -0.120396 0.2794)
			(end 0.12065 0.2794)
			(stroke
				(width 0.1)
				(type default)
			)
			(layer "B.Fab")
		)
		(fp_line
			(start -0.12065 -0.2794)
			(end -0.12065 -0.3048)
			(stroke
				(width 0.1)
				(type default)
			)
			(layer "B.Fab")
		)
		(fp_line
			(start -0.12065 -0.3048)
			(end -0.67945 -0.3048)
			(stroke
				(width 0.1)
				(type default)
			)
			(layer "B.Fab")
		)
		(fp_line
			(start -0.67945 0.3048)
			(end -0.120396 0.3048)
			(stroke
				(width 0.1)
				(type default)
			)
			(layer "B.Fab")
		)
		(fp_line
			(start -0.67945 -0.3048)
			(end -0.67945 0.3048)
			(stroke
				(width 0.1)
				(type default)
			)
			(layer "B.Fab")
		)
		(pad "1" smd circle
			(at 0.40005 0)
			(size 0 0)
			(layers "B.Cu" "B.Mask" "B.Paste")
			(net "LED_POSTCODE_A1")
		)
		(pad "2" smd circle
			(at -0.40005 0)
			(size 0 0)
			(layers "B.Cu" "B.Mask" "B.Paste")
			(net "GND")
		)
	)
	(footprint ""
		(layer "B.Cu")
		(at 44.384214 -30.816804 -90)
		(property "Reference" "R251"
			(at 0 0 90)
			(layer "B.SilkS")
			(hide yes)
			(effects
				(font
					(size 1.27 1.27)
				)
				(justify mirror)
			)
		)
		(property "Value" ""
			(at 0 0 90)
			(layer "B.Fab")
			(effects
				(font
					(size 1.27 1.27)
				)
				(justify mirror)
			)
		)
		(duplicate_pad_numbers_are_jumpers no)
		(fp_line
			(start -0.7874 0.4064)
			(end 0.7874 0.4064)
			(stroke
				(width 0.1524)
				(type default)
			)
			(layer "B.SilkS")
		)
		(fp_line
			(start 0.7874 0.4064)
			(end 0.7874 -0.4064)
			(stroke
				(width 0.1524)
				(type default)
			)
			(layer "B.SilkS")
		)
		(fp_line
			(start -0.7874 -0.4064)
			(end -0.7874 0.4064)
			(stroke
				(width 0.1524)
				(type default)
			)
			(layer "B.SilkS")
		)
		(fp_line
			(start 0.7874 -0.4064)
			(end -0.7874 -0.4064)
			(stroke
				(width 0.1524)
				(type default)
			)
			(layer "B.SilkS")
		)
		(fp_line
			(start -0.67945 0.3048)
			(end -0.120396 0.3048)
			(stroke
				(width 0.1)
				(type default)
			)
			(layer "B.Fab")
		)
		(fp_line
			(start -0.120396 0.3048)
			(end -0.120396 0.2794)
			(stroke
				(width 0.1)
				(type default)
			)
			(layer "B.Fab")
		)
		(fp_line
			(start 0.12065 0.3048)
			(end 0.67945 0.3048)
			(stroke
				(width 0.1)
				(type default)
			)
			(layer "B.Fab")
		)
		(fp_line
			(start 0.67945 0.3048)
			(end 0.67945 -0.305054)
			(stroke
				(width 0.1)
				(type default)
			)
			(layer "B.Fab")
		)
		(fp_line
			(start -0.120396 0.2794)
			(end 0.12065 0.2794)
			(stroke
				(width 0.1)
				(type default)
			)
			(layer "B.Fab")
		)
		(fp_line
			(start 0.12065 0.2794)
			(end 0.12065 0.3048)
			(stroke
				(width 0.1)
				(type default)
			)
			(layer "B.Fab")
		)
		(fp_line
			(start -0.12065 -0.2794)
			(end -0.12065 -0.3048)
			(stroke
				(width 0.1)
				(type default)
			)
			(layer "B.Fab")
		)
		(fp_line
			(start 0.12065 -0.2794)
			(end -0.12065 -0.2794)
			(stroke
				(width 0.1)
				(type default)
			)
			(layer "B.Fab")
		)
		(fp_line
			(start -0.67945 -0.3048)
			(end -0.67945 0.3048)
			(stroke
				(width 0.1)
				(type default)
			)
			(layer "B.Fab")
		)
		(fp_line
			(start -0.12065 -0.3048)
			(end -0.67945 -0.3048)
			(stroke
				(width 0.1)
				(type default)
			)
			(layer "B.Fab")
		)
		(fp_line
			(start 0.12065 -0.305054)
			(end 0.12065 -0.2794)
			(stroke
				(width 0.1)
				(type default)
			)
			(layer "B.Fab")
		)
		(fp_line
			(start 0.67945 -0.305054)
			(end 0.12065 -0.305054)
			(stroke
				(width 0.1)
				(type default)
			)
			(layer "B.Fab")
		)
		(pad "1" smd circle
			(at 0.40005 0 90)
			(size 0 0)
			(layers "B.Cu" "B.Mask" "B.Paste")
			(net "P3V3_AUX")
		)
		(pad "2" smd circle
			(at -0.40005 0 90)
			(size 0 0)
			(layers "B.Cu" "B.Mask" "B.Paste")
			(net "SMB_BMC_MM4_SDA")
		)
	)
)
